# T6G (Grand Teton) — schematic netlist excerpt (pin names and nets, part order shuffled) for the footprints in the layout excerpt that follows; sources: Cadence DE-HDL packaged netlist, KiCad conversion of 04192023_DAF0TMB3IC0_F0TG_MB_C_brd_V02_OCP.brd

R6081  Q_RES  4.7K 5% CHIP  pkg 0402LF  page 28 : A = PVDD11_S3_P0 ; B = SMB_CPU0_2_SCL
C6661  Q_CAP_DIFFBUS  DIFF BUS_0.22UF 6.3V 20% X6S  pkg C0201  page 330 : \1\ = P5E_CPU1_P1_TX_BUF_C_DP<0> ; \2\ = P5E_CPU1_P1_TX_BUF_DP<0>
C6606  Q_CAP_DIFFBUS  DIFF BUS_0.22UF 6.3V 20% X6S  pkg C0201  page 308 : \1\ = P5E_CPU0_P3_TX_BUF_C_DN<4> ; \2\ = P5E_CPU0_P3_TX_BUF_DN<4>

(kicad_pcb
	(version 20260206)
	(generator "pcbnew")
	(generator_version "10.0")
	(general
		(thickness 1.6)
		(legacy_teardrops no)
	)
	(paper "A4")
	(title_block
		(title "04192023_DAF0TMB3IC0_F0TG_MB_C_brd_V02_OCP.brd")
		(comment 1 "Grand Teton / footprints 7342-7344 of 8354")
	)
	(layers
		(0 "F.Cu" signal "TOP")
		(4 "In1.Cu" signal "GND")
		(6 "In2.Cu" signal "IN1")
		(8 "In3.Cu" signal "GND1")
		(10 "In4.Cu" signal "IN2")
		(12 "In5.Cu" signal "GND2")
		(14 "In6.Cu" signal "IN3")
		(16 "In7.Cu" signal "GND3")
		(18 "In8.Cu" signal "VCC")
		(20 "In9.Cu" signal "VCC1")
		(22 "In10.Cu" signal "GND4")
		(24 "In11.Cu" signal "IN4")
		(26 "In12.Cu" signal "GND5")
		(28 "In13.Cu" signal "IN5")
		(30 "In14.Cu" signal "GND6")
		(32 "In15.Cu" signal "IN6")
		(34 "In16.Cu" signal "GND7")
		(2 "B.Cu" signal "BOTTOM")
		(9 "F.Adhes" user "F.Adhesive")
		(11 "B.Adhes" user "B.Adhesive")
		(13 "F.Paste" user "Package Geometry/Pastemask Top")
		(15 "B.Paste" user "Package Geometry/Pastemask Bottom")
		(5 "F.SilkS" user "Ref Des/Silkscreen Top")
		(7 "B.SilkS" user "Ref Des/Silkscreen Bottom")
		(1 "F.Mask" user "Board Geometry/Soldermask Top")
		(3 "B.Mask" user "Board Geometry/Soldermask Bottom")
		(17 "Dwgs.User" user "User.Drawings")
		(19 "Cmts.User" user "User.Comments")
		(21 "Eco1.User" user "User.Eco1")
		(23 "Eco2.User" user "User.Eco2")
		(25 "Edge.Cuts" user "Board Geometry/Outline")
		(27 "Margin" user)
		(31 "F.CrtYd" user "Package Geometry/Place Bound Top")
		(29 "B.CrtYd" user "Package Geometry/Place Bound Bottom")
		(35 "F.Fab" user "Ref Des/Assembly Top")
		(33 "B.Fab" user "Ref Des/Assembly Bottom")
	)
	(footprint ""
		(layer "B.Cu")
		(at 312.403236 -197.836028 -90)
		(property "Reference" "R6081"
			(at 0 0 90)
			(layer "B.SilkS")
			(hide yes)
			(effects
				(font
					(size 1.27 1.27)
				)
				(justify mirror)
			)
		)
		(property "Value" ""
			(at 0 0 90)
			(layer "B.Fab")
			(effects
				(font
					(size 1.27 1.27)
				)
				(justify mirror)
			)
		)
		(duplicate_pad_numbers_are_jumpers no)
		(fp_line
			(start -0.7874 0.4064)
			(end 0.7874 0.4064)
			(stroke
				(width 0.1524)
				(type default)
			)
			(layer "B.SilkS")
		)
		(fp_line
			(start 0.7874 0.4064)
			(end 0.7874 -0.4064)
			(stroke
				(width 0.1524)
				(type default)
			)
			(layer "B.SilkS")
		)
		(fp_line
			(start -0.7874 -0.4064)
			(end -0.7874 0.4064)
			(stroke
				(width 0.1524)
				(type default)
			)
			(layer "B.SilkS")
		)
		(fp_line
			(start 0.7874 -0.4064)
			(end -0.7874 -0.4064)
			(stroke
				(width 0.1524)
				(type default)
			)
			(layer "B.SilkS")
		)
		(fp_line
			(start -0.67945 0.3048)
			(end -0.120396 0.3048)
			(stroke
				(width 0.1)
				(type default)
			)
			(layer "B.Fab")
		)
		(fp_line
			(start -0.120396 0.3048)
			(end -0.120396 0.2794)
			(stroke
				(width 0.1)
				(type default)
			)
			(layer "B.Fab")
		)
		(fp_line
			(start 0.12065 0.3048)
			(end 0.67945 0.3048)
			(stroke
				(width 0.1)
				(type default)
			)
			(layer "B.Fab")
		)
		(fp_line
			(start 0.67945 0.3048)
			(end 0.67945 -0.305054)
			(stroke
				(width 0.1)
				(type default)
			)
			(layer "B.Fab")
		)
		(fp_line
			(start -0.120396 0.2794)
			(end 0.12065 0.2794)
			(stroke
				(width 0.1)
				(type default)
			)
			(layer "B.Fab")
		)
		(fp_line
			(start 0.12065 0.2794)
			(end 0.12065 0.3048)
			(stroke
				(width 0.1)
				(type default)
			)
			(layer "B.Fab")
		)
		(fp_line
			(start -0.12065 -0.2794)
			(end -0.12065 -0.3048)
			(stroke
				(width 0.1)
				(type default)
			)
			(layer "B.Fab")
		)
		(fp_line
			(start 0.12065 -0.2794)
			(end -0.12065 -0.2794)
			(stroke
				(width 0.1)
				(type default)
			)
			(layer "B.Fab")
		)
		(fp_line
			(start -0.67945 -0.3048)
			(end -0.67945 0.3048)
			(stroke
				(width 0.1)
				(type default)
			)
			(layer "B.Fab")
		)
		(fp_line
			(start -0.12065 -0.3048)
			(end -0.67945 -0.3048)
			(stroke
				(width 0.1)
				(type default)
			)
			(layer "B.Fab")
		)
		(fp_line
			(start 0.12065 -0.305054)
			(end 0.12065 -0.2794)
			(stroke
				(width 0.1)
				(type default)
			)
			(layer "B.Fab")
		)
		(fp_line
			(start 0.67945 -0.305054)
			(end 0.12065 -0.305054)
			(stroke
				(width 0.1)
				(type default)
			)
			(layer "B.Fab")
		)
		(pad "1" smd circle
			(at 0.40005 0 90)
			(size 0 0)
			(layers "B.Cu" "B.Mask" "B.Paste")
			(net "PVDD11_S3_P0")
		)
		(pad "2" smd circle
			(at -0.40005 0 90)
			(size 0 0)
			(layers "B.Cu" "B.Mask" "B.Paste")
			(net "SMB_CPU0_2_SCL")
		)
	)
	(footprint ""
		(layer "B.Cu")
		(at 50.214784 -408.517344 90)
		(property "Reference" "C6661"
			(at 0 0 90)
			(layer "B.SilkS")
			(hide yes)
			(effects
				(font
					(size 1.27 1.27)
				)
				(justify mirror)
			)
		)
		(property "Value" ""
			(at 0 0 90)
			(layer "B.Fab")
			(effects
				(font
					(size 1.27 1.27)
				)
				(justify mirror)
			)
		)
		(duplicate_pad_numbers_are_jumpers no)
		(fp_line
			(start 0.299974 -0.150114)
			(end -0.299974 -0.150114)
			(stroke
				(width 0.1)
				(type default)
			)
			(layer "B.Fab")
		)
		(fp_line
			(start -0.299974 -0.150114)
			(end -0.299974 0.150114)
			(stroke
				(width 0.1)
				(type default)
			)
			(layer "B.Fab")
		)
		(fp_line
			(start 0.299974 0.150114)
			(end 0.299974 -0.150114)
			(stroke
				(width 0.1)
				(type default)
			)
			(layer "B.Fab")
		)
		(fp_line
			(start -0.299974 0.150114)
			(end 0.299974 0.150114)
			(stroke
				(width 0.1)
				(type default)
			)
			(layer "B.Fab")
		)
		(pad "1" smd rect
			(at 0.2667 0 270)
			(size 0.3048 0.381)
			(layers "B.Cu" "B.Mask" "B.Paste")
			(net "P5E_CPU1_P1_TX_BUF_C_DP<0>")
		)
		(pad "2" smd rect
			(at -0.2667 0 270)
			(size 0.3048 0.381)
			(layers "B.Cu" "B.Mask" "B.Paste")
			(net "P5E_CPU1_P1_TX_BUF_DP<0>")
		)
	)
	(footprint ""
		(layer "B.Cu")
		(at 384.653282 -416.899344 90)
		(property "Reference" "C6606"
			(at 0 0 90)
			(layer "B.SilkS")
			(hide yes)
			(effects
				(font
					(size 1.27 1.27)
				)
				(justify mirror)
			)
		)
		(property "Value" ""
			(at 0 0 90)
			(layer "B.Fab")
			(effects
				(font
					(size 1.27 1.27)
				)
				(justify mirror)
			)
		)
		(duplicate_pad_numbers_are_jumpers no)
		(fp_line
			(start 0.299974 -0.150114)
			(end -0.299974 -0.150114)
			(stroke
				(width 0.1)
				(type default)
			)
			(layer "B.Fab")
		)
		(fp_line
			(start -0.299974 -0.150114)
			(end -0.299974 0.150114)
			(stroke
				(width 0.1)
				(type default)
			)
			(layer "B.Fab")
		)
		(fp_line
			(start 0.299974 0.150114)
			(end 0.299974 -0.150114)
			(stroke
				(width 0.1)
				(type default)
			)
			(layer "B.Fab")
		)
		(fp_line
			(start -0.299974 0.150114)
			(end 0.299974 0.150114)
			(stroke
				(width 0.1)
				(type default)
			)
			(layer "B.Fab")
		)
		(pad "1" smd rect
			(at 0.2667 0 270)
			(size 0.3048 0.381)
			(layers "B.Cu" "B.Mask" "B.Paste")
			(net "P5E_CPU0_P3_TX_BUF_C_DN<4>")
		)
		(pad "2" smd rect
			(at -0.2667 0 270)
			(size 0.3048 0.381)
			(layers "B.Cu" "B.Mask" "B.Paste")
			(net "P5E_CPU0_P3_TX_BUF_DN<4>")
		)
	)
)
